# T6G (Grand Teton) — schematic netlist excerpt (pin names and nets, part order shuffled) for the footprints in the layout excerpt that follows; sources: Cadence DE-HDL packaged netlist, KiCad conversion of 04192023_DAF0TMB3IC0_F0TG_MB_C_brd_V02_OCP.brd

R540  Q_RES  2.2K 5% CHIP  pkg 0402LF  page 54 : A = CPU1_XTRIG_L7 ; B = PVDD18_S5_P1
PC134  Q_CAP  22UF 16V 20% X6S  pkg C0805  page 192 : A = PVDD_33_S5 ; B = GND
R827  Q_RES  1K 1% CHIP  pkg 0201LF  page 185 : A = P1V8_CPU1_RT_1D ; B = SMB_RT_CPU1_P2_ROM_R_SCL

(kicad_pcb
	(version 20260206)
	(generator "pcbnew")
	(generator_version "10.0")
	(general
		(thickness 1.6)
		(legacy_teardrops no)
	)
	(paper "A4")
	(title_block
		(title "04192023_DAF0TMB3IC0_F0TG_MB_C_brd_V02_OCP.brd")
		(comment 1 "Grand Teton / footprints 8111-8113 of 8354")
	)
	(layers
		(0 "F.Cu" signal "TOP")
		(4 "In1.Cu" signal "GND")
		(6 "In2.Cu" signal "IN1")
		(8 "In3.Cu" signal "GND1")
		(10 "In4.Cu" signal "IN2")
		(12 "In5.Cu" signal "GND2")
		(14 "In6.Cu" signal "IN3")
		(16 "In7.Cu" signal "GND3")
		(18 "In8.Cu" signal "VCC")
		(20 "In9.Cu" signal "VCC1")
		(22 "In10.Cu" signal "GND4")
		(24 "In11.Cu" signal "IN4")
		(26 "In12.Cu" signal "GND5")
		(28 "In13.Cu" signal "IN5")
		(30 "In14.Cu" signal "GND6")
		(32 "In15.Cu" signal "IN6")
		(34 "In16.Cu" signal "GND7")
		(2 "B.Cu" signal "BOTTOM")
		(9 "F.Adhes" user "F.Adhesive")
		(11 "B.Adhes" user "B.Adhesive")
		(13 "F.Paste" user "Package Geometry/Pastemask Top")
		(15 "B.Paste" user "Package Geometry/Pastemask Bottom")
		(5 "F.SilkS" user "Ref Des/Silkscreen Top")
		(7 "B.SilkS" user "Ref Des/Silkscreen Bottom")
		(1 "F.Mask" user "Board Geometry/Soldermask Top")
		(3 "B.Mask" user "Board Geometry/Soldermask Bottom")
		(17 "Dwgs.User" user "User.Drawings")
		(19 "Cmts.User" user "User.Comments")
		(21 "Eco1.User" user "User.Eco1")
		(23 "Eco2.User" user "User.Eco2")
		(25 "Edge.Cuts" user "Board Geometry/Outline")
		(27 "Margin" user)
		(31 "F.CrtYd" user "Package Geometry/Place Bound Top")
		(29 "B.CrtYd" user "Package Geometry/Place Bound Bottom")
		(35 "F.Fab" user "Ref Des/Assembly Top")
		(33 "B.Fab" user "Ref Des/Assembly Bottom")
	)
	(footprint ""
		(layer "B.Cu")
		(at 164.900864 -420.184834 90)
		(property "Reference" "R827"
			(at 0 0 90)
			(layer "B.SilkS")
			(hide yes)
			(effects
				(font
					(size 1.27 1.27)
				)
				(justify mirror)
			)
		)
		(property "Value" ""
			(at 0 0 90)
			(layer "B.Fab")
			(effects
				(font
					(size 1.27 1.27)
				)
				(justify mirror)
			)
		)
		(duplicate_pad_numbers_are_jumpers no)
		(fp_line
			(start 0.32512 -0.175006)
			(end -0.32512 -0.175006)
			(stroke
				(width 0.1)
				(type default)
			)
			(layer "B.Fab")
		)
		(fp_line
			(start -0.32512 -0.175006)
			(end -0.32512 0.175006)
			(stroke
				(width 0.1)
				(type default)
			)
			(layer "B.Fab")
		)
		(fp_line
			(start 0.32512 0.175006)
			(end 0.32512 -0.175006)
			(stroke
				(width 0.1)
				(type default)
			)
			(layer "B.Fab")
		)
		(fp_line
			(start -0.32512 0.175006)
			(end 0.32512 0.175006)
			(stroke
				(width 0.1)
				(type default)
			)
			(layer "B.Fab")
		)
		(pad "1" smd rect
			(at 0.2667 0 270)
			(size 0.3048 0.381)
			(layers "B.Cu" "B.Mask" "B.Paste")
			(net "P1V8_CPU1_RT_1D")
		)
		(pad "2" smd rect
			(at -0.2667 0 90)
			(size 0.3048 0.381)
			(layers "B.Cu" "B.Mask" "B.Paste")
			(net "SMB_RT_CPU1_P2_ROM_R_SCL")
		)
	)
	(footprint ""
		(layer "B.Cu")
		(at 89.614502 -205.14945 90)
		(property "Reference" "R540"
			(at 0 0 90)
			(layer "B.SilkS")
			(hide yes)
			(effects
				(font
					(size 1.27 1.27)
				)
				(justify mirror)
			)
		)
		(property "Value" ""
			(at 0 0 90)
			(layer "B.Fab")
			(effects
				(font
					(size 1.27 1.27)
				)
				(justify mirror)
			)
		)
		(duplicate_pad_numbers_are_jumpers no)
		(fp_line
			(start 0.7874 -0.4064)
			(end -0.7874 -0.4064)
			(stroke
				(width 0.1524)
				(type default)
			)
			(layer "B.SilkS")
		)
		(fp_line
			(start -0.7874 -0.4064)
			(end -0.7874 0.4064)
			(stroke
				(width 0.1524)
				(type default)
			)
			(layer "B.SilkS")
		)
		(fp_line
			(start 0.7874 0.4064)
			(end 0.7874 -0.4064)
			(stroke
				(width 0.1524)
				(type default)
			)
			(layer "B.SilkS")
		)
		(fp_line
			(start -0.7874 0.4064)
			(end 0.7874 0.4064)
			(stroke
				(width 0.1524)
				(type default)
			)
			(layer "B.SilkS")
		)
		(fp_line
			(start 0.67945 -0.305054)
			(end 0.12065 -0.305054)
			(stroke
				(width 0.1)
				(type default)
			)
			(layer "B.Fab")
		)
		(fp_line
			(start 0.12065 -0.305054)
			(end 0.12065 -0.2794)
			(stroke
				(width 0.1)
				(type default)
			)
			(layer "B.Fab")
		)
		(fp_line
			(start -0.12065 -0.3048)
			(end -0.67945 -0.3048)
			(stroke
				(width 0.1)
				(type default)
			)
			(layer "B.Fab")
		)
		(fp_line
			(start -0.67945 -0.3048)
			(end -0.67945 0.3048)
			(stroke
				(width 0.1)
				(type default)
			)
			(layer "B.Fab")
		)
		(fp_line
			(start 0.12065 -0.2794)
			(end -0.12065 -0.2794)
			(stroke
				(width 0.1)
				(type default)
			)
			(layer "B.Fab")
		)
		(fp_line
			(start -0.12065 -0.2794)
			(end -0.12065 -0.3048)
			(stroke
				(width 0.1)
				(type default)
			)
			(layer "B.Fab")
		)
		(fp_line
			(start 0.12065 0.2794)
			(end 0.12065 0.3048)
			(stroke
				(width 0.1)
				(type default)
			)
			(layer "B.Fab")
		)
		(fp_line
			(start -0.120396 0.2794)
			(end 0.12065 0.2794)
			(stroke
				(width 0.1)
				(type default)
			)
			(layer "B.Fab")
		)
		(fp_line
			(start 0.67945 0.3048)
			(end 0.67945 -0.305054)
			(stroke
				(width 0.1)
				(type default)
			)
			(layer "B.Fab")
		)
		(fp_line
			(start 0.12065 0.3048)
			(end 0.67945 0.3048)
			(stroke
				(width 0.1)
				(type default)
			)
			(layer "B.Fab")
		)
		(fp_line
			(start -0.120396 0.3048)
			(end -0.120396 0.2794)
			(stroke
				(width 0.1)
				(type default)
			)
			(layer "B.Fab")
		)
		(fp_line
			(start -0.67945 0.3048)
			(end -0.120396 0.3048)
			(stroke
				(width 0.1)
				(type default)
			)
			(layer "B.Fab")
		)
		(pad "1" smd circle
			(at 0.40005 0 270)
			(size 0 0)
			(layers "B.Cu" "B.Mask" "B.Paste")
			(net "CPU1_XTRIG_L7")
		)
		(pad "2" smd circle
			(at -0.40005 0 270)
			(size 0 0)
			(layers "B.Cu" "B.Mask" "B.Paste")
			(net "PVDD18_S5_P1")
		)
	)
	(footprint ""
		(layer "B.Cu")
		(at 202.00112 -331.027786 -90)
		(property "Reference" "PC134"
			(at 0 0 90)
			(layer "B.SilkS")
			(hide yes)
			(effects
				(font
					(size 1.27 1.27)
				)
				(justify mirror)
			)
		)
		(property "Value" ""
			(at 0 0 90)
			(layer "B.Fab")
			(effects
				(font
					(size 1.27 1.27)
				)
				(justify mirror)
			)
		)
		(duplicate_pad_numbers_are_jumpers no)
		(fp_line
			(start -1.524 0.762)
			(end 1.524 0.762)
			(stroke
				(width 0.1524)
				(type default)
			)
			(layer "B.SilkS")
		)
		(fp_line
			(start 1.524 0.762)
			(end 1.524 -0.762)
			(stroke
				(width 0.1524)
				(type default)
			)
			(layer "B.SilkS")
		)
		(fp_line
			(start -1.524 -0.762)
			(end -1.524 0.762)
			(stroke
				(width 0.1524)
				(type default)
			)
			(layer "B.SilkS")
		)
		(fp_line
			(start 1.524 -0.762)
			(end -1.524 -0.762)
			(stroke
				(width 0.1524)
				(type default)
			)
			(layer "B.SilkS")
		)
		(fp_line
			(start -1.1049 0.724916)
			(end -1.1049 -0.724916)
			(stroke
				(width 0.1)
				(type default)
			)
			(layer "B.Fab")
		)
		(fp_line
			(start 1.1049 0.724916)
			(end -1.1049 0.724916)
			(stroke
				(width 0.1)
				(type default)
			)
			(layer "B.Fab")
		)
		(fp_line
			(start -1.1049 -0.724916)
			(end 1.1049 -0.724916)
			(stroke
				(width 0.1)
				(type default)
			)
			(layer "B.Fab")
		)
		(fp_line
			(start 1.1049 -0.724916)
			(end 1.1049 0.724916)
			(stroke
				(width 0.1)
				(type default)
			)
			(layer "B.Fab")
		)
		(pad "1" smd rect
			(at 0.889 0 270)
			(size 1.016 1.27)
			(layers "B.Cu" "B.Mask" "B.Paste")
			(net "PVDD_33_S5")
		)
		(pad "2" smd rect
			(at -0.889 0 270)
			(size 1.016 1.27)
			(layers "B.Cu" "B.Mask" "B.Paste")
			(net "GND")
		)
	)
)
